# T6G (Grand Teton) — schematic parts with pin connectivity, parts 8196–8221 of 8303; source: Cadence DE-HDL packaged netlist (pstxprt.dat, pstxnet.dat, pstchip.dat)

U263  ISL28022FRZT  ISL28022FRZ-T IC  pkg QFN16_TH_0-5_3X3XH  page 237
  1  A1  IN  = INA230_3_A1
  2  A0  IN  = INA230_3_A0
  3  \ext_clk||int\  BI  = OCP_V3_2_P3V3_ADC_ALERT_R
  4  \sda||smbdat\  BI  = SMB_INA230_3_3V3AUX_SDA_R1
  5  \scl|||smbclk\  IN  = SMB_INA230_3_3V3AUX_SCL_R1
  6  NC0  TRI  = NC_INA230_3_NC0
  7  NC1  TRI  = NC_INA230_3_NC1
  8  NC2  TRI  = NC_INA230_3_NC2
  9  VCC  POWER  = P3V3_AUX
  10  GND  POWER  = GND
  11  VBUS  POWER  = P3V3_OCP_V3_2_R
  12  VINM  IN  = VSENSE_P12V_INA230_3_INN
  13  VINP  IN  = VSENSE_P12V_INA230_3_INP
  14  NC3  TRI  = NC_INA230_3_NC3
  15  NC4  TRI  = NC_INA230_3_NC4
  16  NC5  TRI  = NC_INA230_3_NC5
  TH  TH_GND  POWER  = GND

U264  ISL28022FRZT  ISL28022FRZ-T IC  pkg QFN16_TH_0-5_3X3XH  page 237
  1  A1  IN  = INA230_4_A1
  2  A0  IN  = INA230_4_A0
  3  \ext_clk||int\  BI  = M2_0_P3V3_ADC_ALERT_R
  4  \sda||smbdat\  BI  = SMB_INA230_4_3V3AUX_SDA_R1
  5  \scl|||smbclk\  IN  = SMB_INA230_4_3V3AUX_SCL_R1
  6  NC0  TRI  = NC_INA230_4_NC0
  7  NC1  TRI  = NC_INA230_4_NC1
  8  NC2  TRI  = NC_INA230_4_NC2
  9  VCC  POWER  = P3V3_AUX
  10  GND  POWER  = GND
  11  VBUS  POWER  = P3V3
  12  VINM  IN  = VSENSE_P12V_INA230_4_INN
  13  VINP  IN  = VSENSE_P12V_INA230_4_INP
  14  NC3  TRI  = NC_INA230_4_NC3
  15  NC4  TRI  = NC_INA230_4_NC4
  16  NC5  TRI  = NC_INA230_4_NC5
  TH  TH_GND  POWER  = GND

U265  ISL28022FRZT  ISL28022FRZ-T IC  pkg QFN16_TH_0-5_3X3XH  page 237
  1  A1  IN  = INA230_5_A1
  2  A0  IN  = INA230_5_A0
  3  \ext_clk||int\  BI  = P12V_SCM_ADC_ALERT_R
  4  \sda||smbdat\  BI  = SMB_INA230_5_3V3AUX_SDA_R1
  5  \scl|||smbclk\  IN  = SMB_INA230_5_3V3AUX_SCL_R1
  6  NC0  TRI  = NC_INA230_5_NC0
  7  NC1  TRI  = NC_INA230_5_NC1
  8  NC2  TRI  = NC_INA230_5_NC2
  9  VCC  POWER  = P3V3_AUX
  10  GND  POWER  = GND
  11  VBUS  POWER  = P12V_SCM_R
  12  VINM  IN  = VSENSE_P12V_INA230_5_INN
  13  VINP  IN  = VSENSE_P12V_INA230_5_INP
  14  NC3  TRI  = NC_INA230_5_NC3
  15  NC4  TRI  = NC_INA230_5_NC4
  16  NC5  TRI  = NC_INA230_5_NC5
  TH  TH_GND  POWER  = GND

U266  ISL28022FRZT  ISL28022FRZ-T IC  pkg QFN16_TH_0-5_3X3XH  page 236
  1  A1  IN  = INA230_1_A1
  2  A0  IN  = INA230_1_A0
  3  \ext_clk||int\  BI  = OCP_SFF_P3V3_ADC_ALERT_R
  4  \sda||smbdat\  BI  = SMB_INA230_1_3V3AUX_SDA_R1
  5  \scl|||smbclk\  IN  = SMB_INA230_1_3V3AUX_SCL_R1
  6  NC0  TRI  = NC_INA230_1_NC0
  7  NC1  TRI  = NC_INA230_1_NC1
  8  NC2  TRI  = NC_INA230_1_NC2
  9  VCC  POWER  = P3V3_AUX
  10  GND  POWER  = GND
  11  VBUS  POWER  = P3V3_OCP_SFF_R
  12  VINM  IN  = VSENSE_P3V3_INA230_1_INN
  13  VINP  IN  = VSENSE_P3V3_INA230_1_INP
  14  NC3  TRI  = NC_INA230_1_NC3
  15  NC4  TRI  = NC_INA230_1_NC4
  16  NC5  TRI  = NC_INA230_1_NC5
  TH  TH_GND  POWER  = GND

U268  GL852GOHY60  GL852G-OHY60 IC  pkg QFN28_THXL  page 234
  1  DM0  BI  = USB2_P0_R_DN
  2  DP0  BI  = USB2_P0_R_DP
  3  DM1  BI  = USB2_HUB_SWB_DN
  4  DP1  BI  = USB2_HUB_SWB_DP
  5  AVDD(0)  POWER  = P3V3_AUX_USB_HUB
  6  DM2  BI  = NC_USB_HUB_DM2
  7  DP2  BI  = NC_USB_HUB_DP2
  8  RREF  IN  = USB_HUB_RREF
  9  AVDD(1)  POWER  = P3V3_AUX_USB_HUB
  10  X1  IN  = USB_HUB_XTAL_IN
  11  X2  OUT  = USB_HUB_XTAL_OUT
  12  DM3  BI  = NC_USB_HUB_DM3
  13  DP3  BI  = NC_USB_HUB_DP3
  14  AVDD(2)  POWER  = P3V3_AUX_USB_HUB
  15  DM4  BI  = NC_USB_HUB_DM4
  16  DP4  BI  = NC_USB_HUB_DP4
  17  \reset#\  IN  = RST_USB_HUB_R_N
  18  \test||scl\  BI  = USB_HUB_TEST
  19  \ovcur4#\  IN  = USB_HUB_OVCUR4
  20  \ovcur3#\  IN  = USB_HUB_OVCUR3
  21  DVDD  POWER  = USB_HUB_DVDD
  22  PSELF  IN  = USB_HUB_PSELF
  23  PGANG  BI  = USB_HUB_PGANG
  24  \ovcur2#||smd\  BI  = USB_HUB_OVCUR2
  25  \ovcur1#||smc\  IN  = USB_HUB_OVCUR1
  26  SDA  BI  = NC_USB_HUB_SDA
  27  V5  POWER  = P3V3_AUX_USB_HUB
  28  V33  POWER  = P3V3_AUX_USB_HUB
  TH  TH  POWER  = GND

U269  ADC128D818CIMTXNOPB  ADC128D818CIMTX/NOPB IC  pkg TSSOP16XC  page 257
  1  VREF  IN  = ADC128_VREF
  2  SDA  BI  = SMB_SEN_TIC_3V3AUX_SDA
  3  SCL  IN  = SMB_SEN_TIC_3V3AUX_SCL
  4  GND  POWER  = GND
  5  \v+\  POWER  = P3V3_ADC128_VCC
  6  \int#\  OUT  = TP_ADC128_INT
  7  A0  IN  = ADC128_A0
  8  A1  IN  = ADC128_A1
  9  IN7  IN  = P12V_E1S_0_ISENSE_TIC
  10  IN6  IN  = P3V3_PDB_AUX_ADC_TIC
  11  IN5  IN  = P3V3_AUX_ADC_TIC
  12  IN4  IN  = P3V3_ADC_TIC
  13  IN3  IN  = P5V_ADC_TIC
  14  IN2  IN  = P12V_OCP_V3_2_ISENSE_TIC
  15  IN1  IN  = P12V_OCP_SFF_ISENSE_TIC
  16  IN0  IN  = P12V_AUX_ADC_TIC

U270  LM75BD  IC  pkg SO8_1-27_4-9X3-9  page 235
  1  SDA  BI  = SMB_LM75_0_3V3AUX_SDA_R1
  2  SCL  IN  = SMB_LM75_0_3V3AUX_SCL_R1
  3  OS  OUT  = FM_G751_0_ALERT_N
  4  GND  POWER  = GND
  5  A2  IN  = U270_0_ADD2
  6  A1  IN  = U270_0_ADD1
  7  A0  IN  = U270_0_ADD0
  8  VCC  POWER  = P3V3_AUX

U271  LM75BD  IC  pkg SO8_1-27_4-9X3-9  page 235
  1  SDA  BI  = SMB_LM75_1_3V3AUX_SDA_R1
  2  SCL  IN  = SMB_LM75_1_3V3AUX_SCL_R1
  3  OS  OUT  = FM_G751_1_ALERT_N
  4  GND  POWER  = GND
  5  A2  IN  = U271_1_ADD2
  6  A1  IN  = U271_1_ADD1
  7  A0  IN  = U271_1_ADD0
  8  VCC  POWER  = P3V3_AUX

U272  LM75BD  IC  pkg SO8_1-27_4-9X3-9  page 235
  1  SDA  BI  = SMB_LM75_2_3V3AUX_SDA_R1
  2  SCL  IN  = SMB_LM75_2_3V3AUX_SCL_R1
  3  OS  OUT  = FM_LM75_2_ALERT_N
  4  GND  POWER  = GND
  5  A2  IN  = U272_2_ADD2
  6  A1  IN  = U272_2_ADD1
  7  A0  IN  = U272_2_ADD0
  8  VCC  POWER  = P3V3_AUX

U273  LM75BD  IC  pkg SO8_1-27_4-9X3-9  page 235
  1  SDA  BI  = SMB_LM75_3_3V3AUX_SDA_R1
  2  SCL  IN  = SMB_LM75_3_3V3AUX_SCL_R1
  3  OS  OUT  = FM_LM75_3_ALERT_N
  4  GND  POWER  = GND
  5  A2  IN  = U273_3_ADD2
  6  A1  IN  = U273_3_ADD1
  7  A0  IN  = U273_3_ADD0
  8  VCC  POWER  = P3V3_AUX

U276  ISL28022FRZT  ISL28022FRZ-T IC  pkg QFN16_TH_0-5_3X3XH  page 236
  1  A1  IN  = INA230_2_A1
  2  A0  IN  = INA230_2_A0
  3  \ext_clk||int\  BI  = E1S_0_P3V3_ADC_ALERT_R
  4  \sda||smbdat\  BI  = SMB_INA230_2_3V3AUX_SDA_R1
  5  \scl|||smbclk\  IN  = SMB_INA230_2_3V3AUX_SCL_R1
  6  NC0  TRI  = NC_INA230_2_NC0
  7  NC1  TRI  = NC_INA230_2_NC1
  8  NC2  TRI  = NC_INA230_2_NC2
  9  VCC  POWER  = P3V3_AUX
  10  GND  POWER  = GND
  11  VBUS  POWER  = P3V3_E1S_0_R
  12  VINM  IN  = VSENSE_P3V3_INA230_2_INN
  13  VINP  IN  = VSENSE_P3V3_INA230_2_INP
  14  NC3  TRI  = NC_INA230_2_NC3
  15  NC4  TRI  = NC_INA230_2_NC4
  16  NC5  TRI  = NC_INA230_2_NC5
  TH  TH_GND  POWER  = GND

U278  74LVC1G08W57  74LVC1G08W5-7 IC  pkg SOT25-5_0-95_3X1-6  page 241
  1  A  IN  = FM_GPU_HSC_EN
  2  B  IN  = GPU_PRSNT_R
  3  GND  POWER  = GND
  4  Y  OUT  = FM_GPU_HSC_EN_BUF_R
  5  VCC  POWER  = P3V3_AUX

U279  PCA9617ADP  IC  pkg TSSOP8_3XB  page 148
  1  VCCA  POWER  = P3V3_E1S_0
  2  SCLA  BI  = SMB_E1S_3V3AUX_ISO_SCL_R
  3  SDAA  BI  = SMB_E1S_3V3AUX_ISO_SDA_R
  4  GND  POWER  = GND
  5  EN  IN  = SMB_PCIE_E1S_ISO_EN_R
  6  SDAB  BI  = SMB_SENSOR_E1S_3V3AUX_SDA
  7  SCLB  BI  = SMB_SENSOR_E1S_3V3AUX_SCL
  8  VCCB  POWER  = P3V3_AUX

U286  74LVC1G126SE7  74LVC1G126SE-7 IC  pkg SOT353_0-65_2X1-25  page 138
  1  OE  IN  = OCP_V3_2_AUX_PWR_EN_R1
  2  A  IN  = FM_OCP_V3_2_PWR_GOOD
  3  GND  POWER  = GND
  4  Y  OUT  = FB_BMC_ISOLATE_R2
  5  VCC  POWER  = P3V3_AUX

U290  MOSFET_NCH_GDS_ESD_PROTECTED  2N7002K IC  pkg SOT23_GDSXC  page 268
  D  D  BI  = HSC_EN
  G  G  IN  = PDB_PRSNT_R_N
  S  S  BI  = GND

U308  74LVC2G07DW7  74LVC2G07DW-7 IC  pkg SOT363_0-65_2X1-25XC  page 241
  1  \1a\  IN  = PWRGD_P3V3_AUX_PDB_R
  2  GND  POWER  = GND
  3  \2a\  IN  = NC
  4  \2y\  OUT  = NC
  5  VCC  POWER  = P3V3_AUX
  6  \1y\  OUT  = PWRGD_P3V3_AUX_PDB_BUF_R

U314  9ZXL0451EKILFT  IC  pkg VFQFPN32_TH_0-5_5X5XD  page 182
  1  \^ckpwrgd_pd#\  IN  = FM_9ZXL045_P0_DEV_EN
  2  VDDR  POWER  = P3V3_9ZXL045_P0_VDDR
  3  DIF_IN  IN  = CLK_100M_CPU0_CLK13_DP
  4  \dif_in#\  IN  = CLK_100M_CPU0_CLK13_DN
  5  VSADR0_TRI  IN  = CLK_9ZXL045_P0_SADR0
  6  SMBDAT  BI  = SMB_9ZXL045_P0_SDA
  7  SMBCLK  IN  = SMB_9ZXL045_P0_SCL
  8  \fbout_nc#\  OUT  = NC_U314_FBOUT_N
  9  FBOUT_NC  OUT  = NC_U314_FBOUT
  10  NC0  TRI  = NC_U314_NC0
  11  NC1  TRI  = NC_U314_NC1
  12  VDD0  POWER  = P3V3_9ZXL045_P0_VDD
  13  DIF0  OUT  = CLK_100M_RETIMER_CPU0_P0_R_DP
  14  \dif0#\  OUT  = CLK_100M_RETIMER_CPU0_P0_R_DN
  15  \voe0#\  IN  = FM_9ZXL045_P0_0_OE_N
  16  VDD1  POWER  = P3V3_9ZXL045_P0_VDD
  17  NC2  TRI  = NC_U314_NC2
  18  \voe1#\  IN  = FM_9ZXL045_P0_1_OE_N
  19  DIF1  OUT  = CLK_100M_RETIMER_CPU0_P1_R_DP
  20  \dif1#\  OUT  = CLK_100M_RETIMER_CPU0_P1_R_DN
  21  VDD2  POWER  = P3V3_9ZXL045_P0_VDD
  22  DIF2  OUT  = CLK_100M_RETIMER_CPU0_P2_R_DP
  23  \dif2#\  OUT  = CLK_100M_RETIMER_CPU0_P2_R_DN
  24  \voe2#\  IN  = FM_9ZXL045_P0_2_OE_N
  25  VDD3  POWER  = P3V3_9ZXL045_P0_VDD
  26  \voe3#\  IN  = FM_9ZXL045_P0_3_OE_N
  27  DIF3  OUT  = CLK_100M_RETIMER_CPU0_P3_R_DP
  28  \dif3#\  OUT  = CLK_100M_RETIMER_CPU0_P3_R_DN
  29  VDD4  POWER  = P3V3_9ZXL045_P0_VDD
  30  NC3  TRI  = NC_U314_NC3
  31  VDDA  POWER  = P3V3_9ZXL045_P0_VDDA
  32  \^hibw_bypm_lobw#\  IN  = CLK_9ZXL045_P0_HIBW
  33  EPAD_GND  POWER  = GND

U316  74LVC2G17GW  IC  pkg SOT363  page 124
  1  A0  IN  = SWB_HSC_EN
  2  GND  POWER  = GND
  3  A1  IN  = GND
  4  B1  OUT  = NC_U316_2Y
  5  VCC  POWER  = P3V3_AUX
  6  B0  OUT  = SWB_HSC_EN_BUF_R

U320  74LVC1G66GV  IC  pkg SC74AXA  page 133
  1  Y  BI  = CLK_50M_NCSI_OCP_SFF
  2  Z  BI  = CLK_50M_NCSI_OCP_SFF_ISO_R
  3  GND  POWER  = GND
  4  E  IN  = FB_BMC_ISOLATE
  5  VCC  POWER  = P3V3_AUX

U321  74LVC1G66GV  IC  pkg SC74AXA  page 139
  1  Y  BI  = CLK_50M_NCSI_OCP_V3_2
  2  Z  BI  = CLK_50M_NCSI_OCP_V3_2_ISO_R
  3  GND  POWER  = GND
  4  E  IN  = FB_BMC_ISOLATE1
  5  VCC  POWER  = P3V3_AUX

U324  MOSFET_NCH_GDS_ESD_PROTECTED  2N7002K IC  pkg SOT23_GDSXC  page 188
  D  D  BI  = VR_P5V_EN_D
  G  G  IN  = VR_P5V_EN_N
  S  S  BI  = GND

U325  MOSFET_N  BSS138K EMPTY  pkg SMLF  page 268
  D  DRAIN  OUT  = IRQ_UV_DETECT_N
  G  GATE  IN  = A_P12V_STBY_FPH_GATE
  S  SOURCE  BI  = GND

U326  MPQ8633AGLEC807Z  MPQ8633AGLE-C807-Z IC  pkg QFN14_4X3  page 189
  1  BST  IN  = SW_P5V_AUX_BST
  2  AGND  POWER  = GND
  3  CS  IN  = P5V_AUX_CS
  4  MODE  IN  = P5V_AUX_MODE
  5  TRK_REF  IN  = P5V_AUX_REF
  6  RGND  POWER  = GND
  7  FB  IN  = P5V_AUX_FB
  8  EN  IN  = P5V_AUX_EN
  9  PGOOD  OUT  = PWRGD_P5V_AUX_R
  10  VIN1  IN  = SW_P5V_AUX_FLT
  11_18  PGND  POWER  = GND
  19  VCC  POWER  = P5V_AUX_VCC
  20  SW  OUT  = SW_P5V_AUX_SW
  21  VIN2  IN  = SW_P5V_AUX_FLT

U5201  TUSB211IRWBR  EMPTY  pkg X2QFN12_0-4_1-6X1-6  page 234
  1  D1M  BI  = USB2_HUB_BUF_SWB_R_DN
  2  D1P  BI  = USB2_HUB_BUF_SWB_R_DP
  3  TEST  IN  = TP_USB2_TEST
  4  CD  OUT  = TP_USB2_CD
  5  RSTN  IN  = PD_U5201_RSTN
  6  EQ  IN  = PD_U5201_EQ
  7  D2P  BI  = USB2_HUB_BUF_SWB_R_DP
  8  D2M  BI  = USB2_HUB_BUF_SWB_R_DN
  9  ENA_HS  OUT  = TP_USB2_ENA_HS
  10  GND  POWER  = GND
  11  VREG  OUT  = PD_U5201_VREG
  12  VCC  POWER  = P3V3_AUX

U6000  DS125BR111RTWR  IC  pkg WQFN24_TH_0-5_4X4XA  page 112
  1  \eqb0||ad3\  IN  = FM_P2E_BUF2_EQB0
  2  \eqb1||ad2\  IN  = FM_P2E_BUF2_EQB1
  3  ENSMB  IN  = PD_P2E_BUF2_ENSMB
  4  \sda||voda_db\  BI  = FM_P2E_BUF2_VODA_DB
  5  \scl||vodb_db\  BI  = FM_P2E_BUF2_VODB_DB
  6  PWDN  IN  = FM_P2E_EN2_N
  7  \outa+\  OUT  = P2E_MB_BMC_TX_BUF2_DP<0>
  8  \outa-\  OUT  = P2E_MB_BMC_TX_BUF2_DN<0>
  9  \eqa1||ad1\  IN  = FM_P2E_BUF2_EQA1
  10  \eqa0||ad0\  IN  = FM_P2E_BUF2_EQA0
  11  \inb+\  IN  = P2E_MB_BMC_RX_R2_DP<0>
  12  \inb-\  IN  = P2E_MB_BMC_RX_R2_DN<0>
  13  RES  IN  = NC_RES
  14  SD_TH  IN  = FM_P2E_BUF2_SD_TH
  15  VIN  POWER  = P3V3_AUX
  16  VDD_SEL  IN  = GND
  17  \vod_sel||readen#\  IN  = FM_P2E_BUF2_VOD_SEL
  18  \rxdet||done#\  BI  = FM_P2E_BUF2_RXDET
  19  \outb-\  OUT  = P2E_MB_BMC_RX_BUF2_C_DN<0>
  20  \outb+\  OUT  = P2E_MB_BMC_RX_BUF2_C_DP<0>
  21  VDD_21  POWER  = BUF2_VDD
  22  VDD_22  POWER  = BUF2_VDD
  23  \ina-\  IN  = P2E_MB_BMC_TX_C_R2_DN<0>
  24  \ina+\  IN  = P2E_MB_BMC_TX_C_R2_DP<0>
  25  TH_GND  POWER  = GND

U6001  CYUSB330468LTXI  CYUSB3304-68LTXI IC  pkg QFN68_TH_0-4_8X8  page 176
  1  DVDD12_1  POWER  = P1V2_CPU0_USB_DVDD12
  2  RREF_USB2  BI  = USB_CPU0_HUB1_RREF_USB2
  3  DVDD12_2  POWER  = P1V2_CPU0_USB_DVDD12
  4  AVDD33_1  POWER  = P3V3_AUX_CPU0_USB_AVDD33
  5  US_TXM  OUT  = USB3_CPU0_BMC_RX_HUB1_DN
  6  US_TXP  OUT  = USB3_CPU0_BMC_RX_HUB1_DP
  7  DVDD12_5  POWER  = P1V2_AUX
  8  US_RXM  IN  = USB3_CPU0_BMC_TX_C1_DN
  9  US_RXP  IN  = USB3_CPU0_BMC_TX_C1_DP
  10  AVDD12_1  POWER  = P1V2_AUX
  11  DS4_TXP  OUT  = NC
  12  DS4_TXM  OUT  = NC
  13  DVDD12_6  POWER  = P1V2_AUX
  14  DS4_RXM  IN  = NC
  15  DS4_RXP  IN  = NC
  16  AVDD12_2  POWER  = P1V2_AUX
  17  VBUS_US  POWER  = USB_CPU0_HUB1_VBUS_US
  18  VBUS_DS  POWER  = USB_CPU0_HUB1_VBUS_DS
  19  VDD_EFUSE  POWER  = P1V2_CPU0_USB_DVDD12
  20  SUSPEND  BI  = TP_CPU0_USB_HUB1_SUSPEND
  21  RESERVED1  BI  = PU_CPU0_USB_HUB_RESERVED1
  22  RESERVED2  BI  = PU_CPU0_USB_HUB_RESERVED2
  23  MODE_SEL0  IN  = USB_CPU0_HUB1_MODE_SEL0
  24  MODE_SEL1  IN  = USB_CPU0_HUB1_MODE_SEL1
  25  NC_25  TRI  = NC
  26  RREF_SS  BI  = USB_CPU0_HUB1_RREF_SS
  27  DVDD12_3  POWER  = P1V2_CPU0_USB_DVDD12
  28  VDD_IO  POWER  = P3V3_AUX
  29  PWR_EN  BI  = PU_CPU0_USB_HUB_PWR_EN
  30  OVRCURR  IN  = PU_CPU0_USB_HUB_OVRCURR
  31  \reset#\  IN  = RST_USB_CPU0_HUB1_R_N
  32  I2C_CLK  BI  = SMB_USB_CPU0_HUB1_SCL
  33  I2C_DATA  BI  = SMB_USB_CPU0_HUB1_SDA
  34  AVDD12_3  POWER  = P1V2_AUX
  35  DS3_RXP  IN  = NC
  36  DS3_RXM  IN  = NC
  37  DVDD12_7  POWER  = P1V2_AUX
  38  DS3_TXP  OUT  = NC
  39  DS3_TXM  OUT  = NC
  40  GND  POWER  = GND
  41  DS2_TXP  OUT  = NC
  42  DS2_TXM  OUT  = NC
  43  DVDD12_8  POWER  = P1V2_AUX
  44  DS2_RXM  IN  = NC
  45  DS2_RXP  IN  = NC
  46  AVDD12_4  POWER  = P1V2_AUX
  47  DS1_TXP  OUT  = USB3_CPU0_BMC_HUB1_TX_DP
  48  DS1_TXM  OUT  = USB3_CPU0_BMC_HUB1_TX_DN
  49  DVDD12_4  POWER  = P1V2_AUX
  50  DS1_RXM  IN  = USB3_CPU0_BMC_RX_C1_DN
  51  DS1_RXP  IN  = USB3_CPU0_BMC_RX_C1_DP
  52  AVDD12_5  POWER  = P1V2_AUX
  53  AVDD12_6  POWER  = P1V2_AUX
  54  XTL_OUT  OUT  = XTAL_USB_CPU0_HUB1_XOUT
  55  XTL_IN  IN  = XTAL_USB_CPU0_HUB1_XIN
  56  AVDD33_2  POWER  = P3V3_AUX
  57  US_DP  BI  = USB2_CPU0_P0_R1_DP
  58  US_DM  BI  = USB2_CPU0_P0_R1_DN
  59  DS1_DM  BI  = USB2_CPU0_P0_HUB1_R_DN
  60  DS1_DP  BI  = USB2_CPU0_P0_HUB1_R_DP
  61  AVDD33_3  POWER  = P3V3_AUX
  62  DS2_DP  BI  = NC
  63  DS2_DM  BI  = NC
  64  DS3_DM  BI  = NC
  65  DS3_DP  BI  = NC
  66  AVDD33_4  POWER  = P3V3_AUX
  67  DS4_DP  BI  = NC
  68  DS4_DM  BI  = NC
  TH  EPAD  POWER  = GND
